(kicad_pcb
	(version 20260206)
	(generator "pcbnew")
	(generator_version "10.0")
	(general
		(thickness 1.6)
		(legacy_teardrops no)
	)
	(paper "A4")
	(title_block
		(title "Bryce Canyon_IOM_M2_16342-2_OCP.brd")
		(comment 1 "Bryce Canyon / footprints 49-56 of 1146")
	)
	(layers
		(0 "F.Cu" signal "TOP")
		(4 "In1.Cu" signal "L2GND")
		(6 "In2.Cu" signal "L3")
		(8 "In3.Cu" signal "L4VCC")
		(10 "In4.Cu" signal "L5VCC")
		(12 "In5.Cu" signal "L6")
		(14 "In6.Cu" signal "L7GND")
		(2 "B.Cu" signal "BOTTOM")
		(9 "F.Adhes" user "F.Adhesive")
		(11 "B.Adhes" user "B.Adhesive")
		(13 "F.Paste" user "Package Geometry/Pastemask Top")
		(15 "B.Paste" user "Package Geometry/Pastemask Bottom")
		(5 "F.SilkS" user "Ref Des/Silkscreen Top")
		(7 "B.SilkS" user "Ref Des/Silkscreen Bottom")
		(1 "F.Mask" user "Board Geometry/Soldermask Top")
		(3 "B.Mask" user "Board Geometry/Soldermask Bottom")
		(17 "Dwgs.User" user "User.Drawings")
		(19 "Cmts.User" user "User.Comments")
		(21 "Eco1.User" user "User.Eco1")
		(23 "Eco2.User" user "User.Eco2")
		(25 "Edge.Cuts" user "Board Geometry/Outline")
		(27 "Margin" user)
		(31 "F.CrtYd" user "Package Geometry/Place Bound Top")
		(29 "B.CrtYd" user "Package Geometry/Place Bound Bottom")
		(35 "F.Fab" user "Ref Des/Assembly Top")
		(33 "B.Fab" user "Ref Des/Assembly Bottom")
	)
	(footprint ""
		(layer "F.Cu")
		(at 32.3342 -162.687 180)
		(property "Reference" "C102"
			(at 0 0 180)
			(layer "F.SilkS")
			(hide yes)
			(effects
				(font
					(size 1.27 1.27)
				)
			)
		)
		(property "Value" "SC1U16V3KX-5GP"
			(at 0 -2.8194 180)
			(unlocked yes)
			(layer "F.Fab")
			(hide yes)
			(effects
				(font
					(size 1.016 1.016)
					(thickness 0.1524)
				)
			)
		)
		(property "Device Type" "C603H36"
			(at 0 -4.3434 180)
			(unlocked yes)
			(layer "F.Fab")
			(hide yes)
			(effects
				(font
					(size 1.016 1.016)
					(thickness 0.1524)
				)
			)
		)
		(duplicate_pad_numbers_are_jumpers no)
		(fp_line
			(start 0.508 0)
			(end -0.508 0)
			(stroke
				(width 0.2032)
				(type default)
			)
			(layer "F.SilkS")
		)
		(fp_rect
			(start -0.5842 1.3335)
			(end 0.5842 -1.3335)
			(stroke
				(width 0)
				(type default)
			)
			(fill no)
			(layer "F.CrtYd")
		)
		(fp_rect
			(start -0.5842 1.3335)
			(end 0.5842 -1.3335)
			(stroke
				(width 0)
				(type default)
			)
			(fill no)
			(layer "F.Fab")
		)
		(pad "1" smd custom
			(at 0 -0.762 180)
			(size 0.2159 0.2159)
			(layers "F.Cu" "F.Mask" "F.Paste")
			(net "V1PLLAV11")
			(options
				(clearance outline)
				(anchor circle)
			)
			(primitives
				(gr_poly
					(pts
						(arc
							(start -0.3302 -0.4318)
							(mid -0.402042 -0.402042)
							(end -0.4318 -0.3302)
						)
						(arc
							(start -0.4318 0.3302)
							(mid -0.402042 0.402042)
							(end -0.3302 0.4318)
						)
						(arc
							(start 0.3302 0.4318)
							(mid 0.402042 0.402042)
							(end 0.4318 0.3302)
						)
						(arc
							(start 0.4318 -0.3302)
							(mid 0.402042 -0.402042)
							(end 0.3302 -0.4318)
						)
					)
					(width 0)
					(fill yes)
				)
			)
		)
		(pad "2" smd custom
			(at 0 0.762 180)
			(size 0.2159 0.2159)
			(layers "F.Cu" "F.Mask" "F.Paste")
			(net "GND")
			(options
				(clearance outline)
				(anchor circle)
			)
			(primitives
				(gr_poly
					(pts
						(arc
							(start -0.3302 -0.4318)
							(mid -0.402042 -0.402042)
							(end -0.4318 -0.3302)
						)
						(arc
							(start -0.4318 0.3302)
							(mid -0.402042 0.402042)
							(end -0.3302 0.4318)
						)
						(arc
							(start 0.3302 0.4318)
							(mid 0.402042 0.402042)
							(end 0.4318 0.3302)
						)
						(arc
							(start 0.4318 -0.3302)
							(mid 0.402042 -0.402042)
							(end 0.3302 -0.4318)
						)
					)
					(width 0)
					(fill yes)
				)
			)
		)
	)
	(footprint ""
		(layer "F.Cu")
		(at 203.5048 -99.441)
		(property "Reference" "R559"
			(at 0 0 0)
			(layer "F.SilkS")
			(hide yes)
			(effects
				(font
					(size 1.27 1.27)
				)
			)
		)
		(property "Value" "0R2J-2-GP"
			(at 0.064008 -3.993896 0)
			(unlocked yes)
			(layer "F.Fab")
			(hide yes)
			(effects
				(font
					(size 1.016 1.016)
					(thickness 0.1524)
				)
			)
		)
		(property "Device Type" "R402H16"
			(at 0.064008 -5.517896 0)
			(unlocked yes)
			(layer "F.Fab")
			(hide yes)
			(effects
				(font
					(size 1.016 1.016)
					(thickness 0.1524)
				)
			)
		)
		(duplicate_pad_numbers_are_jumpers no)
		(fp_line
			(start -0.508 -0.9398)
			(end -0.508 0.9398)
			(stroke
				(width 0.1524)
				(type default)
			)
			(layer "F.SilkS")
		)
		(fp_line
			(start 0.508 -0.9398)
			(end -0.508 -0.9398)
			(stroke
				(width 0.1524)
				(type default)
			)
			(layer "F.SilkS")
		)
		(fp_rect
			(start -0.508 0.9398)
			(end 0.508 -0.9398)
			(stroke
				(width 0)
				(type default)
			)
			(fill no)
			(layer "F.CrtYd")
		)
		(fp_rect
			(start -0.508 0.9398)
			(end 0.508 -0.9398)
			(stroke
				(width 0)
				(type default)
			)
			(fill no)
			(layer "F.Fab")
		)
		(pad "1" smd custom
			(at 0 -0.4445)
			(size 0.1397 0.1397)
			(layers "F.Cu" "F.Mask" "F.Paste")
			(net "TEMP_2_SCL")
			(options
				(clearance outline)
				(anchor circle)
			)
			(primitives
				(gr_poly
					(pts
						(arc
							(start -0.1778 -0.2794)
							(mid -0.249642 -0.249642)
							(end -0.2794 -0.1778)
						)
						(arc
							(start -0.2794 0.1778)
							(mid -0.249642 0.249642)
							(end -0.1778 0.2794)
						)
						(arc
							(start 0.1778 0.2794)
							(mid 0.249642 0.249642)
							(end 0.2794 0.1778)
						)
						(arc
							(start 0.2794 -0.1778)
							(mid 0.249642 -0.249642)
							(end 0.1778 -0.2794)
						)
					)
					(width 0)
					(fill yes)
				)
			)
		)
		(pad "2" smd custom
			(at 0 0.4445)
			(size 0.1397 0.1397)
			(layers "F.Cu" "F.Mask" "F.Paste")
			(net "I2C_IOM_SCL")
			(options
				(clearance outline)
				(anchor circle)
			)
			(primitives
				(gr_poly
					(pts
						(arc
							(start -0.1778 -0.2794)
							(mid -0.249642 -0.249642)
							(end -0.2794 -0.1778)
						)
						(arc
							(start -0.2794 0.1778)
							(mid -0.249642 0.249642)
							(end -0.1778 0.2794)
						)
						(arc
							(start 0.1778 0.2794)
							(mid 0.249642 0.249642)
							(end 0.2794 0.1778)
						)
						(arc
							(start 0.2794 -0.1778)
							(mid 0.249642 -0.249642)
							(end 0.1778 -0.2794)
						)
					)
					(width 0)
					(fill yes)
				)
			)
		)
	)
	(footprint ""
		(layer "F.Cu")
		(at 85.487256 -141.090142 -90)
		(property "Reference" "R617"
			(at 0 0 270)
			(layer "F.SilkS")
			(hide yes)
			(effects
				(font
					(size 1.27 1.27)
				)
			)
		)
		(property "Value" "0R2J-2-GP"
			(at 0.064008 -3.993896 270)
			(unlocked yes)
			(layer "F.Fab")
			(hide yes)
			(effects
				(font
					(size 1.016 1.016)
					(thickness 0.1524)
				)
			)
		)
		(property "Device Type" "R402H16"
			(at 0.064008 -5.517896 270)
			(unlocked yes)
			(layer "F.Fab")
			(hide yes)
			(effects
				(font
					(size 1.016 1.016)
					(thickness 0.1524)
				)
			)
		)
		(duplicate_pad_numbers_are_jumpers no)
		(fp_line
			(start -0.508 -0.9398)
			(end -0.508 0.9398)
			(stroke
				(width 0.1524)
				(type default)
			)
			(layer "F.SilkS")
		)
		(fp_line
			(start 0.508 -0.9398)
			(end -0.508 -0.9398)
			(stroke
				(width 0.1524)
				(type default)
			)
			(layer "F.SilkS")
		)
		(fp_rect
			(start -0.508 0.9398)
			(end 0.508 -0.9398)
			(stroke
				(width 0)
				(type default)
			)
			(fill no)
			(layer "F.CrtYd")
		)
		(fp_rect
			(start -0.508 0.9398)
			(end 0.508 -0.9398)
			(stroke
				(width 0)
				(type default)
			)
			(fill no)
			(layer "F.Fab")
		)
		(pad "1" smd custom
			(at 0 -0.4445 270)
			(size 0.1397 0.1397)
			(layers "F.Cu" "F.Mask" "F.Paste")
			(net "I2C_DPB_SDA")
			(options
				(clearance outline)
				(anchor circle)
			)
			(primitives
				(gr_poly
					(pts
						(arc
							(start -0.1778 -0.2794)
							(mid -0.249642 -0.249642)
							(end -0.2794 -0.1778)
						)
						(arc
							(start -0.2794 0.1778)
							(mid -0.249642 0.249642)
							(end -0.1778 0.2794)
						)
						(arc
							(start 0.1778 0.2794)
							(mid 0.249642 0.249642)
							(end 0.2794 0.1778)
						)
						(arc
							(start 0.2794 -0.1778)
							(mid 0.249642 -0.249642)
							(end 0.1778 -0.2794)
						)
					)
					(width 0)
					(fill yes)
				)
			)
		)
		(pad "2" smd custom
			(at 0 0.4445 270)
			(size 0.1397 0.1397)
			(layers "F.Cu" "F.Mask" "F.Paste")
			(net "I2C_DPB_SDA_R")
			(options
				(clearance outline)
				(anchor circle)
			)
			(primitives
				(gr_poly
					(pts
						(arc
							(start -0.1778 -0.2794)
							(mid -0.249642 -0.249642)
							(end -0.2794 -0.1778)
						)
						(arc
							(start -0.2794 0.1778)
							(mid -0.249642 0.249642)
							(end -0.1778 0.2794)
						)
						(arc
							(start 0.1778 0.2794)
							(mid 0.249642 0.249642)
							(end 0.2794 0.1778)
						)
						(arc
							(start 0.2794 -0.1778)
							(mid 0.249642 -0.249642)
							(end 0.1778 -0.2794)
						)
					)
					(width 0)
					(fill yes)
				)
			)
		)
	)
	(footprint ""
		(layer "F.Cu")
		(at 99.3902 -151.6888 90)
		(property "Reference" "R43"
			(at 0 0 90)
			(layer "F.SilkS")
			(hide yes)
			(effects
				(font
					(size 1.27 1.27)
				)
			)
		)
		(property "Value" "4K7R2F-GP"
			(at 0.064008 -3.993896 90)
			(unlocked yes)
			(layer "F.Fab")
			(hide yes)
			(effects
				(font
					(size 1.016 1.016)
					(thickness 0.1524)
				)
			)
		)
		(property "Device Type" "R402H16"
			(at 0.064008 -5.517896 90)
			(unlocked yes)
			(layer "F.Fab")
			(hide yes)
			(effects
				(font
					(size 1.016 1.016)
					(thickness 0.1524)
				)
			)
		)
		(duplicate_pad_numbers_are_jumpers no)
		(fp_line
			(start 0.508 -0.9398)
			(end -0.508 -0.9398)
			(stroke
				(width 0.1524)
				(type default)
			)
			(layer "F.SilkS")
		)
		(fp_line
			(start -0.508 -0.9398)
			(end -0.508 0.9398)
			(stroke
				(width 0.1524)
				(type default)
			)
			(layer "F.SilkS")
		)
		(fp_rect
			(start -0.508 0.9398)
			(end 0.508 -0.9398)
			(stroke
				(width 0)
				(type default)
			)
			(fill no)
			(layer "F.CrtYd")
		)
		(fp_rect
			(start -0.508 0.9398)
			(end 0.508 -0.9398)
			(stroke
				(width 0)
				(type default)
			)
			(fill no)
			(layer "F.Fab")
		)
		(pad "1" smd custom
			(at 0 -0.4445 90)
			(size 0.1397 0.1397)
			(layers "F.Cu" "F.Mask" "F.Paste")
			(net "USB_EN_4")
			(options
				(clearance outline)
				(anchor circle)
			)
			(primitives
				(gr_poly
					(pts
						(arc
							(start -0.1778 -0.2794)
							(mid -0.249642 -0.249642)
							(end -0.2794 -0.1778)
						)
						(arc
							(start -0.2794 0.1778)
							(mid -0.249642 0.249642)
							(end -0.1778 0.2794)
						)
						(arc
							(start 0.1778 0.2794)
							(mid 0.249642 0.249642)
							(end 0.2794 0.1778)
						)
						(arc
							(start 0.2794 -0.1778)
							(mid 0.249642 -0.249642)
							(end 0.1778 -0.2794)
						)
					)
					(width 0)
					(fill yes)
				)
			)
		)
		(pad "2" smd custom
			(at 0 0.4445 90)
			(size 0.1397 0.1397)
			(layers "F.Cu" "F.Mask" "F.Paste")
			(net "GND")
			(options
				(clearance outline)
				(anchor circle)
			)
			(primitives
				(gr_poly
					(pts
						(arc
							(start -0.1778 -0.2794)
							(mid -0.249642 -0.249642)
							(end -0.2794 -0.1778)
						)
						(arc
							(start -0.2794 0.1778)
							(mid -0.249642 0.249642)
							(end -0.1778 0.2794)
						)
						(arc
							(start 0.1778 0.2794)
							(mid 0.249642 0.249642)
							(end 0.2794 0.1778)
						)
						(arc
							(start 0.2794 -0.1778)
							(mid 0.249642 -0.249642)
							(end 0.1778 -0.2794)
						)
					)
					(width 0)
					(fill yes)
				)
			)
		)
	)
	(footprint ""
		(layer "F.Cu")
		(at 224.185988 -18.469356)
		(property "Reference" "C164"
			(at 0 0 0)
			(layer "F.SilkS")
			(hide yes)
			(effects
				(font
					(size 1.27 1.27)
				)
			)
		)
		(property "Value" "SC10U16V5KX-7-GP-U"
			(at -0.0762 -6.1214 0)
			(unlocked yes)
			(layer "F.Fab")
			(hide yes)
			(effects
				(font
					(size 1.016 1.016)
					(thickness 0.1524)
				)
			)
		)
		(property "Device Type" "C805H58"
			(at -0.0762 -8.1534 0)
			(unlocked yes)
			(layer "F.Fab")
			(hide yes)
			(effects
				(font
					(size 1.016 1.016)
					(thickness 0.1524)
				)
			)
		)
		(duplicate_pad_numbers_are_jumpers no)
		(fp_line
			(start 0.635 0)
			(end -0.635 0)
			(stroke
				(width 0.508)
				(type default)
			)
			(layer "F.SilkS")
		)
		(fp_rect
			(start -0.9652 1.778)
			(end 0.9652 -1.778)
			(stroke
				(width 0)
				(type default)
			)
			(fill no)
			(layer "F.CrtYd")
		)
		(fp_poly
			(pts
				(xy -0.9652 -1.778) (xy 0.9652 -1.778) (xy 0.9652 1.778) (xy -0.9652 1.778)
			)
			(stroke
				(width 0)
				(type default)
			)
			(fill no)
			(layer "F.Fab")
		)
		(pad "1" smd rect
			(at 0 -0.9652)
			(size 1.397 1.143)
			(layers "F.Cu" "F.Mask" "F.Paste")
			(net "P5V_STBY")
		)
		(pad "2" smd rect
			(at 0 0.9652)
			(size 1.397 1.143)
			(layers "F.Cu" "F.Mask" "F.Paste")
			(net "GND")
		)
	)
	(footprint ""
		(layer "F.Cu")
		(at 147.854416 -11.675618 -90)
		(property "Reference" "C209"
			(at 0 0 270)
			(layer "F.SilkS")
			(hide yes)
			(effects
				(font
					(size 1.27 1.27)
				)
			)
		)
		(property "Value" "SC1U16V3KX-5GP"
			(at 0 -2.8194 270)
			(unlocked yes)
			(layer "F.Fab")
			(hide yes)
			(effects
				(font
					(size 1.016 1.016)
					(thickness 0.1524)
				)
			)
		)
		(property "Device Type" "C603H36"
			(at 0 -4.3434 270)
			(unlocked yes)
			(layer "F.Fab")
			(hide yes)
			(effects
				(font
					(size 1.016 1.016)
					(thickness 0.1524)
				)
			)
		)
		(duplicate_pad_numbers_are_jumpers no)
		(fp_line
			(start 0.508 0)
			(end -0.508 0)
			(stroke
				(width 0.2032)
				(type default)
			)
			(layer "F.SilkS")
		)
		(fp_rect
			(start -0.5842 1.3335)
			(end 0.5842 -1.3335)
			(stroke
				(width 0)
				(type default)
			)
			(fill no)
			(layer "F.CrtYd")
		)
		(fp_rect
			(start -0.5842 1.3335)
			(end 0.5842 -1.3335)
			(stroke
				(width 0)
				(type default)
			)
			(fill no)
			(layer "F.Fab")
		)
		(pad "1" smd custom
			(at 0 -0.762 270)
			(size 0.2159 0.2159)
			(layers "F.Cu" "F.Mask" "F.Paste")
			(net "P1V8_STBY_VRG5")
			(options
				(clearance outline)
				(anchor circle)
			)
			(primitives
				(gr_poly
					(pts
						(arc
							(start -0.3302 -0.4318)
							(mid -0.402042 -0.402042)
							(end -0.4318 -0.3302)
						)
						(arc
							(start -0.4318 0.3302)
							(mid -0.402042 0.402042)
							(end -0.3302 0.4318)
						)
						(arc
							(start 0.3302 0.4318)
							(mid 0.402042 0.402042)
							(end 0.4318 0.3302)
						)
						(arc
							(start 0.4318 -0.3302)
							(mid 0.402042 -0.402042)
							(end 0.3302 -0.4318)
						)
					)
					(width 0)
					(fill yes)
				)
			)
		)
		(pad "2" smd custom
			(at 0 0.762 270)
			(size 0.2159 0.2159)
			(layers "F.Cu" "F.Mask" "F.Paste")
			(net "GND")
			(options
				(clearance outline)
				(anchor circle)
			)
			(primitives
				(gr_poly
					(pts
						(arc
							(start -0.3302 -0.4318)
							(mid -0.402042 -0.402042)
							(end -0.4318 -0.3302)
						)
						(arc
							(start -0.4318 0.3302)
							(mid -0.402042 0.402042)
							(end -0.3302 0.4318)
						)
						(arc
							(start 0.3302 0.4318)
							(mid 0.402042 0.402042)
							(end 0.4318 0.3302)
						)
						(arc
							(start 0.4318 -0.3302)
							(mid 0.402042 -0.402042)
							(end 0.3302 -0.4318)
						)
					)
					(width 0)
					(fill yes)
				)
			)
		)
	)
	(footprint ""
		(layer "F.Cu")
		(at 120.0658 -15.9766)
		(property "Reference" "R441"
			(at 0 0 0)
			(layer "F.SilkS")
			(hide yes)
			(effects
				(font
					(size 1.27 1.27)
				)
			)
		)
		(property "Value" "10R2F-L-GP"
			(at 0.064008 -3.993896 0)
			(unlocked yes)
			(layer "F.Fab")
			(hide yes)
			(effects
				(font
					(size 1.016 1.016)
					(thickness 0.1524)
				)
			)
		)
		(property "Device Type" "R402H14"
			(at 0.064008 -5.517896 0)
			(unlocked yes)
			(layer "F.Fab")
			(hide yes)
			(effects
				(font
					(size 1.016 1.016)
					(thickness 0.1524)
				)
			)
		)
		(duplicate_pad_numbers_are_jumpers no)
		(fp_line
			(start -0.508 -0.9398)
			(end -0.508 0.9398)
			(stroke
				(width 0.1524)
				(type default)
			)
			(layer "F.SilkS")
		)
		(fp_line
			(start 0.508 -0.9398)
			(end -0.508 -0.9398)
			(stroke
				(width 0.1524)
				(type default)
			)
			(layer "F.SilkS")
		)
		(fp_rect
			(start -0.508 0.9398)
			(end 0.508 -0.9398)
			(stroke
				(width 0)
				(type default)
			)
			(fill no)
			(layer "F.CrtYd")
		)
		(fp_rect
			(start -0.508 0.9398)
			(end 0.508 -0.9398)
			(stroke
				(width 0)
				(type default)
			)
			(fill no)
			(layer "F.Fab")
		)
		(pad "1" smd custom
			(at 0 -0.4445)
			(size 0.1397 0.1397)
			(layers "F.Cu" "F.Mask" "F.Paste")
			(net "MB0_CM_SENSE_R1_N")
			(options
				(clearance outline)
				(anchor circle)
			)
			(primitives
				(gr_poly
					(pts
						(arc
							(start -0.1778 -0.2794)
							(mid -0.249642 -0.249642)
							(end -0.2794 -0.1778)
						)
						(arc
							(start -0.2794 0.1778)
							(mid -0.249642 0.249642)
							(end -0.1778 0.2794)
						)
						(arc
							(start 0.1778 0.2794)
							(mid 0.249642 0.249642)
							(end 0.2794 0.1778)
						)
						(arc
							(start 0.2794 -0.1778)
							(mid 0.249642 -0.249642)
							(end 0.1778 -0.2794)
						)
					)
					(width 0)
					(fill yes)
				)
			)
		)
		(pad "2" smd custom
			(at 0 0.4445)
			(size 0.1397 0.1397)
			(layers "F.Cu" "F.Mask" "F.Paste")
			(net "MB0_CM_SENSE_N")
			(options
				(clearance outline)
				(anchor circle)
			)
			(primitives
				(gr_poly
					(pts
						(arc
							(start -0.1778 -0.2794)
							(mid -0.249642 -0.249642)
							(end -0.2794 -0.1778)
						)
						(arc
							(start -0.2794 0.1778)
							(mid -0.249642 0.249642)
							(end -0.1778 0.2794)
						)
						(arc
							(start 0.1778 0.2794)
							(mid 0.249642 0.249642)
							(end 0.2794 0.1778)
						)
						(arc
							(start 0.2794 -0.1778)
							(mid 0.249642 -0.249642)
							(end 0.1778 -0.2794)
						)
					)
					(width 0)
					(fill yes)
				)
			)
		)
	)
	(footprint ""
		(layer "F.Cu")
		(at 65.741042 -159.091884)
		(property "Reference" "C518"
			(at 0 0 0)
			(layer "F.SilkS")
			(hide yes)
			(effects
				(font
					(size 1.27 1.27)
				)
			)
		)
		(property "Value" "SCD1U25V2KX-2-GP"
			(at 1.1811 -2.7051 0)
			(unlocked yes)
			(layer "F.Fab")
			(hide yes)
			(effects
				(font
					(size 1.016 1.016)
					(thickness 0.1524)
				)
			)
		)
		(property "Device Type" "C402H22"
			(at 1.1811 -4.2291 0)
			(unlocked yes)
			(layer "F.Fab")
			(hide yes)
			(effects
				(font
					(size 1.016 1.016)
					(thickness 0.1524)
				)
			)
		)
		(duplicate_pad_numbers_are_jumpers no)
		(fp_rect
			(start -0.4318 0.9525)
			(end 0.4318 -0.9525)
			(stroke
				(width 0)
				(type default)
			)
			(fill no)
			(layer "F.CrtYd")
		)
		(fp_rect
			(start -0.4318 0.9525)
			(end 0.4318 -0.9525)
			(stroke
				(width 0)
				(type default)
			)
			(fill no)
			(layer "F.Fab")
		)
		(pad "1" smd custom
			(at 0 -0.4445)
			(size 0.1524 0.1524)
			(layers "F.Cu" "F.Mask" "F.Paste")
			(net "ADC_P1V15_STBY")
			(options
				(clearance outline)
				(anchor circle)
			)
			(primitives
				(gr_poly
					(pts
						(arc
							(start 0.3048 -0.2032)
							(mid 0.275042 -0.275042)
							(end 0.2032 -0.3048)
						)
						(arc
							(start -0.2032 -0.3048)
							(mid -0.275042 -0.275042)
							(end -0.3048 -0.2032)
						)
						(arc
							(start -0.3048 0.2032)
							(mid -0.275042 0.275042)
							(end -0.2032 0.3048)
						)
						(arc
							(start 0.2032 0.3048)
							(mid 0.275042 0.275042)
							(end 0.3048 0.2032)
						)
					)
					(width 0)
					(fill yes)
				)
			)
		)
		(pad "2" smd custom
			(at 0 0.4445)
			(size 0.1524 0.1524)
			(layers "F.Cu" "F.Mask" "F.Paste")
			(net "GND")
			(options
				(clearance outline)
				(anchor circle)
			)
			(primitives
				(gr_poly
					(pts
						(arc
							(start 0.3048 -0.2032)
							(mid 0.275042 -0.275042)
							(end 0.2032 -0.3048)
						)
						(arc
							(start -0.2032 -0.3048)
							(mid -0.275042 -0.275042)
							(end -0.3048 -0.2032)
						)
						(arc
							(start -0.3048 0.2032)
							(mid -0.275042 0.275042)
							(end -0.2032 0.3048)
						)
						(arc
							(start 0.2032 0.3048)
							(mid 0.275042 0.275042)
							(end 0.3048 0.2032)
						)
					)
					(width 0)
					(fill yes)
				)
			)
		)
	)
)
